(kicad_pcb
	(version 20260206)
	(generator "pcbnew")
	(generator_version "10.0")
	(general
		(thickness 1.6)
		(legacy_teardrops no)
	)
	(paper "A4")
	(title_block
		(title "01162023_DA0F0TEBIF0_F0T_Expander_BD_F_brd_V02_OCP.brd")
		(comment 1 "Grand Teton / footprints 816-822 of 9728")
	)
	(layers
		(0 "F.Cu" signal "TOP")
		(4 "In1.Cu" signal "GND")
		(6 "In2.Cu" signal "VCC")
		(8 "In3.Cu" signal "VCC1")
		(10 "In4.Cu" signal "GND1")
		(12 "In5.Cu" signal "IN1")
		(14 "In6.Cu" signal "GND2")
		(16 "In7.Cu" signal "IN2")
		(18 "In8.Cu" signal "GND3")
		(20 "In9.Cu" signal "IN3")
		(22 "In10.Cu" signal "GND4")
		(24 "In11.Cu" signal "IN4")
		(26 "In12.Cu" signal "GND5")
		(28 "In13.Cu" signal "IN5")
		(30 "In14.Cu" signal "GND6")
		(32 "In15.Cu" signal "IN6")
		(34 "In16.Cu" signal "GND7")
		(2 "B.Cu" signal "BOTTOM")
		(9 "F.Adhes" user "F.Adhesive")
		(11 "B.Adhes" user "B.Adhesive")
		(13 "F.Paste" user "Package Geometry/Pastemask Top")
		(15 "B.Paste" user "Package Geometry/Pastemask Bottom")
		(5 "F.SilkS" user "Ref Des/Silkscreen Top")
		(7 "B.SilkS" user "Ref Des/Silkscreen Bottom")
		(1 "F.Mask" user "Board Geometry/Soldermask Top")
		(3 "B.Mask" user "Board Geometry/Soldermask Bottom")
		(17 "Dwgs.User" user "User.Drawings")
		(19 "Cmts.User" user "User.Comments")
		(21 "Eco1.User" user "User.Eco1")
		(23 "Eco2.User" user "User.Eco2")
		(25 "Edge.Cuts" user "Board Geometry/Outline")
		(27 "Margin" user)
		(31 "F.CrtYd" user "Package Geometry/Place Bound Top")
		(29 "B.CrtYd" user "Package Geometry/Place Bound Bottom")
		(35 "F.Fab" user "Ref Des/Assembly Top")
		(33 "B.Fab" user "Ref Des/Assembly Bottom")
	)
	(footprint ""
		(layer "F.Cu")
		(at 277.67153 -25.342342 -90)
		(property "Reference" "R436"
			(at 0 0 270)
			(layer "F.SilkS")
			(hide yes)
			(effects
				(font
					(size 1.27 1.27)
				)
			)
		)
		(property "Value" ""
			(at 0 0 270)
			(layer "F.Fab")
			(effects
				(font
					(size 1.27 1.27)
				)
			)
		)
		(duplicate_pad_numbers_are_jumpers no)
		(fp_line
			(start -0.7874 0.4064)
			(end -0.7874 -0.4064)
			(stroke
				(width 0.1524)
				(type default)
			)
			(layer "F.SilkS")
		)
		(fp_line
			(start 0.7874 0.4064)
			(end -0.7874 0.4064)
			(stroke
				(width 0.1524)
				(type default)
			)
			(layer "F.SilkS")
		)
		(fp_line
			(start -0.7874 -0.4064)
			(end 0.7874 -0.4064)
			(stroke
				(width 0.1524)
				(type default)
			)
			(layer "F.SilkS")
		)
		(fp_line
			(start 0.7874 -0.4064)
			(end 0.7874 0.4064)
			(stroke
				(width 0.1524)
				(type default)
			)
			(layer "F.SilkS")
		)
		(fp_line
			(start -0.67945 0.3048)
			(end -0.67945 -0.305054)
			(stroke
				(width 0.1)
				(type default)
			)
			(layer "F.Fab")
		)
		(fp_line
			(start -0.12065 0.3048)
			(end -0.67945 0.3048)
			(stroke
				(width 0.1)
				(type default)
			)
			(layer "F.Fab")
		)
		(fp_line
			(start 0.120396 0.3048)
			(end 0.120396 0.2794)
			(stroke
				(width 0.1)
				(type default)
			)
			(layer "F.Fab")
		)
		(fp_line
			(start 0.67945 0.3048)
			(end 0.120396 0.3048)
			(stroke
				(width 0.1)
				(type default)
			)
			(layer "F.Fab")
		)
		(fp_line
			(start -0.12065 0.2794)
			(end -0.12065 0.3048)
			(stroke
				(width 0.1)
				(type default)
			)
			(layer "F.Fab")
		)
		(fp_line
			(start 0.120396 0.2794)
			(end -0.12065 0.2794)
			(stroke
				(width 0.1)
				(type default)
			)
			(layer "F.Fab")
		)
		(fp_line
			(start -0.12065 -0.2794)
			(end 0.12065 -0.2794)
			(stroke
				(width 0.1)
				(type default)
			)
			(layer "F.Fab")
		)
		(fp_line
			(start 0.12065 -0.2794)
			(end 0.12065 -0.3048)
			(stroke
				(width 0.1)
				(type default)
			)
			(layer "F.Fab")
		)
		(fp_line
			(start 0.12065 -0.3048)
			(end 0.67945 -0.3048)
			(stroke
				(width 0.1)
				(type default)
			)
			(layer "F.Fab")
		)
		(fp_line
			(start 0.67945 -0.3048)
			(end 0.67945 0.3048)
			(stroke
				(width 0.1)
				(type default)
			)
			(layer "F.Fab")
		)
		(fp_line
			(start -0.67945 -0.305054)
			(end -0.12065 -0.305054)
			(stroke
				(width 0.1)
				(type default)
			)
			(layer "F.Fab")
		)
		(fp_line
			(start -0.12065 -0.305054)
			(end -0.12065 -0.2794)
			(stroke
				(width 0.1)
				(type default)
			)
			(layer "F.Fab")
		)
		(pad "1" smd circle
			(at -0.40005 0 270)
			(size 0 0)
			(layers "F.Cu" "F.Mask" "F.Paste")
			(net "P3V3_SSD9")
		)
		(pad "2" smd circle
			(at 0.40005 0 270)
			(size 0 0)
			(layers "F.Cu" "F.Mask" "F.Paste")
			(net "DUALPORT_N_SSD9")
		)
	)
	(footprint ""
		(layer "F.Cu")
		(at 467.68893 -524.540988 180)
		(property "Reference" "SCREW_SSD1_1"
			(at -5.207 -1.402334 0)
			(unlocked yes)
			(layer "B.SilkS")
			(effects
				(font
					(size 0.7874 0.5842)
					(thickness 0.1524)
				)
				(justify mirror)
			)
		)
		(property "Value" ""
			(at 0 0 180)
			(layer "F.Fab")
			(effects
				(font
					(size 1.27 1.27)
				)
			)
		)
		(duplicate_pad_numbers_are_jumpers no)
		(pad "1" thru_hole circle
			(at 0 0 180)
			(size 0.4572 0.4572)
			(drill 0.2032)
			(layers "*.Cu" "*.Mask")
			(remove_unused_layers no)
			(net "Net_9142")
			(clearance 0.127)
			(thermal_gap 0.127)
			(padstack
				(mode front_inner_back)
				(layer "Inner"
					(shape circle)
					(size 0.4572 0.4572)
					(clearance 0.127)
				)
				(layer "B.Cu"
					(shape circle)
					(size 0.508 0.508)
					(clearance 0.1016)
				)
			)
		)
	)
	(footprint ""
		(layer "F.Cu")
		(at 249.733562 -209.590386)
		(property "Reference" "R5538"
			(at 0 0 0)
			(layer "F.SilkS")
			(hide yes)
			(effects
				(font
					(size 1.27 1.27)
				)
			)
		)
		(property "Value" ""
			(at 0 0 0)
			(layer "F.Fab")
			(effects
				(font
					(size 1.27 1.27)
				)
			)
		)
		(duplicate_pad_numbers_are_jumpers no)
		(fp_line
			(start -0.7874 -0.4064)
			(end 0.7874 -0.4064)
			(stroke
				(width 0.1524)
				(type default)
			)
			(layer "F.SilkS")
		)
		(fp_line
			(start -0.7874 0.4064)
			(end -0.7874 -0.4064)
			(stroke
				(width 0.1524)
				(type default)
			)
			(layer "F.SilkS")
		)
		(fp_line
			(start 0.7874 -0.4064)
			(end 0.7874 0.4064)
			(stroke
				(width 0.1524)
				(type default)
			)
			(layer "F.SilkS")
		)
		(fp_line
			(start 0.7874 0.4064)
			(end -0.7874 0.4064)
			(stroke
				(width 0.1524)
				(type default)
			)
			(layer "F.SilkS")
		)
		(fp_line
			(start -0.67945 -0.305054)
			(end -0.12065 -0.305054)
			(stroke
				(width 0.1)
				(type default)
			)
			(layer "F.Fab")
		)
		(fp_line
			(start -0.67945 0.3048)
			(end -0.67945 -0.305054)
			(stroke
				(width 0.1)
				(type default)
			)
			(layer "F.Fab")
		)
		(fp_line
			(start -0.12065 -0.305054)
			(end -0.12065 -0.2794)
			(stroke
				(width 0.1)
				(type default)
			)
			(layer "F.Fab")
		)
		(fp_line
			(start -0.12065 -0.2794)
			(end 0.12065 -0.2794)
			(stroke
				(width 0.1)
				(type default)
			)
			(layer "F.Fab")
		)
		(fp_line
			(start -0.12065 0.2794)
			(end -0.12065 0.3048)
			(stroke
				(width 0.1)
				(type default)
			)
			(layer "F.Fab")
		)
		(fp_line
			(start -0.12065 0.3048)
			(end -0.67945 0.3048)
			(stroke
				(width 0.1)
				(type default)
			)
			(layer "F.Fab")
		)
		(fp_line
			(start 0.120396 0.2794)
			(end -0.12065 0.2794)
			(stroke
				(width 0.1)
				(type default)
			)
			(layer "F.Fab")
		)
		(fp_line
			(start 0.120396 0.3048)
			(end 0.120396 0.2794)
			(stroke
				(width 0.1)
				(type default)
			)
			(layer "F.Fab")
		)
		(fp_line
			(start 0.12065 -0.3048)
			(end 0.67945 -0.3048)
			(stroke
				(width 0.1)
				(type default)
			)
			(layer "F.Fab")
		)
		(fp_line
			(start 0.12065 -0.2794)
			(end 0.12065 -0.3048)
			(stroke
				(width 0.1)
				(type default)
			)
			(layer "F.Fab")
		)
		(fp_line
			(start 0.67945 -0.3048)
			(end 0.67945 0.3048)
			(stroke
				(width 0.1)
				(type default)
			)
			(layer "F.Fab")
		)
		(fp_line
			(start 0.67945 0.3048)
			(end 0.120396 0.3048)
			(stroke
				(width 0.1)
				(type default)
			)
			(layer "F.Fab")
		)
		(pad "1" smd circle
			(at -0.40005 0)
			(size 0 0)
			(layers "F.Cu" "F.Mask" "F.Paste")
			(net "PWRGD_P1V2_AUX_R")
		)
		(pad "2" smd circle
			(at 0.40005 0)
			(size 0 0)
			(layers "F.Cu" "F.Mask" "F.Paste")
			(net "PWRGD_P1V2_AUX")
		)
	)
	(footprint ""
		(layer "F.Cu")
		(at 58.995056 -97.718372 180)
		(property "Reference" "R99"
			(at 0 0 180)
			(layer "F.SilkS")
			(hide yes)
			(effects
				(font
					(size 1.27 1.27)
				)
			)
		)
		(property "Value" ""
			(at 0 0 180)
			(layer "F.Fab")
			(effects
				(font
					(size 1.27 1.27)
				)
			)
		)
		(duplicate_pad_numbers_are_jumpers no)
		(fp_line
			(start 0.7874 0.4064)
			(end -0.7874 0.4064)
			(stroke
				(width 0.1524)
				(type default)
			)
			(layer "F.SilkS")
		)
		(fp_line
			(start 0.7874 -0.4064)
			(end 0.7874 0.4064)
			(stroke
				(width 0.1524)
				(type default)
			)
			(layer "F.SilkS")
		)
		(fp_line
			(start -0.7874 0.4064)
			(end -0.7874 -0.4064)
			(stroke
				(width 0.1524)
				(type default)
			)
			(layer "F.SilkS")
		)
		(fp_line
			(start -0.7874 -0.4064)
			(end 0.7874 -0.4064)
			(stroke
				(width 0.1524)
				(type default)
			)
			(layer "F.SilkS")
		)
		(fp_line
			(start 0.67945 0.3048)
			(end 0.120396 0.3048)
			(stroke
				(width 0.1)
				(type default)
			)
			(layer "F.Fab")
		)
		(fp_line
			(start 0.67945 -0.3048)
			(end 0.67945 0.3048)
			(stroke
				(width 0.1)
				(type default)
			)
			(layer "F.Fab")
		)
		(fp_line
			(start 0.12065 -0.2794)
			(end 0.12065 -0.3048)
			(stroke
				(width 0.1)
				(type default)
			)
			(layer "F.Fab")
		)
		(fp_line
			(start 0.12065 -0.3048)
			(end 0.67945 -0.3048)
			(stroke
				(width 0.1)
				(type default)
			)
			(layer "F.Fab")
		)
		(fp_line
			(start 0.120396 0.3048)
			(end 0.120396 0.2794)
			(stroke
				(width 0.1)
				(type default)
			)
			(layer "F.Fab")
		)
		(fp_line
			(start 0.120396 0.2794)
			(end -0.12065 0.2794)
			(stroke
				(width 0.1)
				(type default)
			)
			(layer "F.Fab")
		)
		(fp_line
			(start -0.12065 0.3048)
			(end -0.67945 0.3048)
			(stroke
				(width 0.1)
				(type default)
			)
			(layer "F.Fab")
		)
		(fp_line
			(start -0.12065 0.2794)
			(end -0.12065 0.3048)
			(stroke
				(width 0.1)
				(type default)
			)
			(layer "F.Fab")
		)
		(fp_line
			(start -0.12065 -0.2794)
			(end 0.12065 -0.2794)
			(stroke
				(width 0.1)
				(type default)
			)
			(layer "F.Fab")
		)
		(fp_line
			(start -0.12065 -0.305054)
			(end -0.12065 -0.2794)
			(stroke
				(width 0.1)
				(type default)
			)
			(layer "F.Fab")
		)
		(fp_line
			(start -0.67945 0.3048)
			(end -0.67945 -0.305054)
			(stroke
				(width 0.1)
				(type default)
			)
			(layer "F.Fab")
		)
		(fp_line
			(start -0.67945 -0.305054)
			(end -0.12065 -0.305054)
			(stroke
				(width 0.1)
				(type default)
			)
			(layer "F.Fab")
		)
		(pad "1" smd circle
			(at -0.40005 0 180)
			(size 0 0)
			(layers "F.Cu" "F.Mask" "F.Paste")
			(net "RST_NIC1_PERST3_R_N")
		)
		(pad "2" smd circle
			(at 0.40005 0 180)
			(size 0 0)
			(layers "F.Cu" "F.Mask" "F.Paste")
			(net "RST_HP_NIC1_BUF_N")
		)
	)
	(footprint ""
		(layer "F.Cu")
		(at 340.320884 -116.230654 -90)
		(property "Reference" "R953"
			(at 0 0 270)
			(layer "F.SilkS")
			(hide yes)
			(effects
				(font
					(size 1.27 1.27)
				)
			)
		)
		(property "Value" ""
			(at 0 0 270)
			(layer "F.Fab")
			(effects
				(font
					(size 1.27 1.27)
				)
			)
		)
		(duplicate_pad_numbers_are_jumpers no)
		(fp_line
			(start -0.7874 0.4064)
			(end -0.7874 -0.4064)
			(stroke
				(width 0.1524)
				(type default)
			)
			(layer "F.SilkS")
		)
		(fp_line
			(start 0.7874 0.4064)
			(end -0.7874 0.4064)
			(stroke
				(width 0.1524)
				(type default)
			)
			(layer "F.SilkS")
		)
		(fp_line
			(start -0.7874 -0.4064)
			(end 0.7874 -0.4064)
			(stroke
				(width 0.1524)
				(type default)
			)
			(layer "F.SilkS")
		)
		(fp_line
			(start 0.7874 -0.4064)
			(end 0.7874 0.4064)
			(stroke
				(width 0.1524)
				(type default)
			)
			(layer "F.SilkS")
		)
		(fp_line
			(start -0.67945 0.3048)
			(end -0.67945 -0.305054)
			(stroke
				(width 0.1)
				(type default)
			)
			(layer "F.Fab")
		)
		(fp_line
			(start -0.12065 0.3048)
			(end -0.67945 0.3048)
			(stroke
				(width 0.1)
				(type default)
			)
			(layer "F.Fab")
		)
		(fp_line
			(start 0.120396 0.3048)
			(end 0.120396 0.2794)
			(stroke
				(width 0.1)
				(type default)
			)
			(layer "F.Fab")
		)
		(fp_line
			(start 0.67945 0.3048)
			(end 0.120396 0.3048)
			(stroke
				(width 0.1)
				(type default)
			)
			(layer "F.Fab")
		)
		(fp_line
			(start -0.12065 0.2794)
			(end -0.12065 0.3048)
			(stroke
				(width 0.1)
				(type default)
			)
			(layer "F.Fab")
		)
		(fp_line
			(start 0.120396 0.2794)
			(end -0.12065 0.2794)
			(stroke
				(width 0.1)
				(type default)
			)
			(layer "F.Fab")
		)
		(fp_line
			(start -0.12065 -0.2794)
			(end 0.12065 -0.2794)
			(stroke
				(width 0.1)
				(type default)
			)
			(layer "F.Fab")
		)
		(fp_line
			(start 0.12065 -0.2794)
			(end 0.12065 -0.3048)
			(stroke
				(width 0.1)
				(type default)
			)
			(layer "F.Fab")
		)
		(fp_line
			(start 0.12065 -0.3048)
			(end 0.67945 -0.3048)
			(stroke
				(width 0.1)
				(type default)
			)
			(layer "F.Fab")
		)
		(fp_line
			(start 0.67945 -0.3048)
			(end 0.67945 0.3048)
			(stroke
				(width 0.1)
				(type default)
			)
			(layer "F.Fab")
		)
		(fp_line
			(start -0.67945 -0.305054)
			(end -0.12065 -0.305054)
			(stroke
				(width 0.1)
				(type default)
			)
			(layer "F.Fab")
		)
		(fp_line
			(start -0.12065 -0.305054)
			(end -0.12065 -0.2794)
			(stroke
				(width 0.1)
				(type default)
			)
			(layer "F.Fab")
		)
		(pad "1" smd circle
			(at -0.40005 0 270)
			(size 0 0)
			(layers "F.Cu" "F.Mask" "F.Paste")
			(net "P3V3_AUX")
		)
		(pad "2" smd circle
			(at 0.40005 0 270)
			(size 0 0)
			(layers "F.Cu" "F.Mask" "F.Paste")
			(net "PWRGD_P12V_NIC5_CO")
		)
	)
	(footprint ""
		(layer "F.Cu")
		(at 238.124746 -114.666268)
		(property "Reference" "PC636"
			(at 0 0 0)
			(layer "F.SilkS")
			(hide yes)
			(effects
				(font
					(size 1.27 1.27)
				)
			)
		)
		(property "Value" ""
			(at 0 0 0)
			(layer "F.Fab")
			(effects
				(font
					(size 1.27 1.27)
				)
			)
		)
		(duplicate_pad_numbers_are_jumpers no)
		(fp_line
			(start -0.7874 -0.4064)
			(end 0.7874 -0.4064)
			(stroke
				(width 0.1524)
				(type default)
			)
			(layer "F.SilkS")
		)
		(fp_line
			(start -0.7874 0.4064)
			(end -0.7874 -0.4064)
			(stroke
				(width 0.1524)
				(type default)
			)
			(layer "F.SilkS")
		)
		(fp_line
			(start 0.7874 -0.4064)
			(end 0.7874 0.4064)
			(stroke
				(width 0.1524)
				(type default)
			)
			(layer "F.SilkS")
		)
		(fp_line
			(start 0.7874 0.4064)
			(end -0.7874 0.4064)
			(stroke
				(width 0.1524)
				(type default)
			)
			(layer "F.SilkS")
		)
		(fp_line
			(start -0.67945 -0.305054)
			(end -0.12065 -0.305054)
			(stroke
				(width 0.1)
				(type default)
			)
			(layer "F.Fab")
		)
		(fp_line
			(start -0.67945 0.3048)
			(end -0.67945 -0.305054)
			(stroke
				(width 0.1)
				(type default)
			)
			(layer "F.Fab")
		)
		(fp_line
			(start -0.12065 -0.305054)
			(end -0.12065 -0.2794)
			(stroke
				(width 0.1)
				(type default)
			)
			(layer "F.Fab")
		)
		(fp_line
			(start -0.12065 -0.2794)
			(end 0.12065 -0.2794)
			(stroke
				(width 0.1)
				(type default)
			)
			(layer "F.Fab")
		)
		(fp_line
			(start -0.12065 0.2794)
			(end -0.12065 0.3048)
			(stroke
				(width 0.1)
				(type default)
			)
			(layer "F.Fab")
		)
		(fp_line
			(start -0.12065 0.3048)
			(end -0.67945 0.3048)
			(stroke
				(width 0.1)
				(type default)
			)
			(layer "F.Fab")
		)
		(fp_line
			(start 0.120396 0.2794)
			(end -0.12065 0.2794)
			(stroke
				(width 0.1)
				(type default)
			)
			(layer "F.Fab")
		)
		(fp_line
			(start 0.120396 0.3048)
			(end 0.120396 0.2794)
			(stroke
				(width 0.1)
				(type default)
			)
			(layer "F.Fab")
		)
		(fp_line
			(start 0.12065 -0.3048)
			(end 0.67945 -0.3048)
			(stroke
				(width 0.1)
				(type default)
			)
			(layer "F.Fab")
		)
		(fp_line
			(start 0.12065 -0.2794)
			(end 0.12065 -0.3048)
			(stroke
				(width 0.1)
				(type default)
			)
			(layer "F.Fab")
		)
		(fp_line
			(start 0.67945 -0.3048)
			(end 0.67945 0.3048)
			(stroke
				(width 0.1)
				(type default)
			)
			(layer "F.Fab")
		)
		(fp_line
			(start 0.67945 0.3048)
			(end 0.120396 0.3048)
			(stroke
				(width 0.1)
				(type default)
			)
			(layer "F.Fab")
		)
		(pad "1" smd circle
			(at -0.40005 0)
			(size 0 0)
			(layers "F.Cu" "F.Mask" "F.Paste")
			(net "P12V_NIC3_CO_TIMER")
		)
		(pad "2" smd circle
			(at 0.40005 0)
			(size 0 0)
			(layers "F.Cu" "F.Mask" "F.Paste")
			(net "GND")
		)
	)
	(footprint ""
		(layer "F.Cu")
		(at 368.78768 -25.342342 -90)
		(property "Reference" "R447"
			(at 0 0 270)
			(layer "F.SilkS")
			(hide yes)
			(effects
				(font
					(size 1.27 1.27)
				)
			)
		)
		(property "Value" ""
			(at 0 0 270)
			(layer "F.Fab")
			(effects
				(font
					(size 1.27 1.27)
				)
			)
		)
		(duplicate_pad_numbers_are_jumpers no)
		(fp_line
			(start -0.7874 0.4064)
			(end -0.7874 -0.4064)
			(stroke
				(width 0.1524)
				(type default)
			)
			(layer "F.SilkS")
		)
		(fp_line
			(start 0.7874 0.4064)
			(end -0.7874 0.4064)
			(stroke
				(width 0.1524)
				(type default)
			)
			(layer "F.SilkS")
		)
		(fp_line
			(start -0.7874 -0.4064)
			(end 0.7874 -0.4064)
			(stroke
				(width 0.1524)
				(type default)
			)
			(layer "F.SilkS")
		)
		(fp_line
			(start 0.7874 -0.4064)
			(end 0.7874 0.4064)
			(stroke
				(width 0.1524)
				(type default)
			)
			(layer "F.SilkS")
		)
		(fp_line
			(start -0.67945 0.3048)
			(end -0.67945 -0.305054)
			(stroke
				(width 0.1)
				(type default)
			)
			(layer "F.Fab")
		)
		(fp_line
			(start -0.12065 0.3048)
			(end -0.67945 0.3048)
			(stroke
				(width 0.1)
				(type default)
			)
			(layer "F.Fab")
		)
		(fp_line
			(start 0.120396 0.3048)
			(end 0.120396 0.2794)
			(stroke
				(width 0.1)
				(type default)
			)
			(layer "F.Fab")
		)
		(fp_line
			(start 0.67945 0.3048)
			(end 0.120396 0.3048)
			(stroke
				(width 0.1)
				(type default)
			)
			(layer "F.Fab")
		)
		(fp_line
			(start -0.12065 0.2794)
			(end -0.12065 0.3048)
			(stroke
				(width 0.1)
				(type default)
			)
			(layer "F.Fab")
		)
		(fp_line
			(start 0.120396 0.2794)
			(end -0.12065 0.2794)
			(stroke
				(width 0.1)
				(type default)
			)
			(layer "F.Fab")
		)
		(fp_line
			(start -0.12065 -0.2794)
			(end 0.12065 -0.2794)
			(stroke
				(width 0.1)
				(type default)
			)
			(layer "F.Fab")
		)
		(fp_line
			(start 0.12065 -0.2794)
			(end 0.12065 -0.3048)
			(stroke
				(width 0.1)
				(type default)
			)
			(layer "F.Fab")
		)
		(fp_line
			(start 0.12065 -0.3048)
			(end 0.67945 -0.3048)
			(stroke
				(width 0.1)
				(type default)
			)
			(layer "F.Fab")
		)
		(fp_line
			(start 0.67945 -0.3048)
			(end 0.67945 0.3048)
			(stroke
				(width 0.1)
				(type default)
			)
			(layer "F.Fab")
		)
		(fp_line
			(start -0.67945 -0.305054)
			(end -0.12065 -0.305054)
			(stroke
				(width 0.1)
				(type default)
			)
			(layer "F.Fab")
		)
		(fp_line
			(start -0.12065 -0.305054)
			(end -0.12065 -0.2794)
			(stroke
				(width 0.1)
				(type default)
			)
			(layer "F.Fab")
		)
		(pad "1" smd circle
			(at -0.40005 0 270)
			(size 0 0)
			(layers "F.Cu" "F.Mask" "F.Paste")
			(net "GND")
		)
		(pad "2" smd circle
			(at 0.40005 0 270)
			(size 0 0)
			(layers "F.Cu" "F.Mask" "F.Paste")
			(net "DUALPORT_N_SSD12")
		)
	)
)
